(kicad_pcb
	(version 20241229)
	(generator "pcbnew")
	(generator_version "9.0")
	(general
		(thickness 1.62)
		(legacy_teardrops no)
	)
	(paper "A4")
	(title_block
		(title "OCuLink to 10GbE adapter")
		(date "2026-02-23")
		(rev "1.1.0")
		(company "Antmicro Ltd")
		(comment 1 "www.antmicro.com")
		(comment 9 "footprints 48-52 of 510")
	)
	(layers
		(0 "F.Cu" signal)
		(4 "In1.Cu" signal)
		(6 "In2.Cu" signal)
		(8 "In3.Cu" signal)
		(10 "In4.Cu" signal)
		(12 "In5.Cu" signal)
		(14 "In6.Cu" signal)
		(2 "B.Cu" signal)
		(9 "F.Adhes" user "F.Adhesive")
		(11 "B.Adhes" user "B.Adhesive")
		(13 "F.Paste" user)
		(15 "B.Paste" user)
		(5 "F.SilkS" user "F.Silkscreen")
		(7 "B.SilkS" user "B.Silkscreen")
		(1 "F.Mask" user)
		(3 "B.Mask" user)
		(17 "Dwgs.User" user "User.Drawings")
		(19 "Cmts.User" user "User.Comments")
		(21 "Eco1.User" user "User.Eco1")
		(23 "Eco2.User" user "User.Eco2")
		(25 "Edge.Cuts" user)
		(27 "Margin" user)
		(31 "F.CrtYd" user "F.Courtyard")
		(29 "B.CrtYd" user "B.Courtyard")
		(35 "F.Fab" user)
		(33 "B.Fab" user)
	)
	(footprint "antmicro-footprints:L_Bourns-SRP4021HMT"
		(layer "F.Cu")
		(at 60.249999 103.850001 180)
		(property "Reference" "L3"
			(at -4.030001 0.220001 0)
			(layer "F.SilkS")
			(effects
				(font
					(size 0.7 0.7)
					(thickness 0.15)
				)
				(justify right top)
			)
		)
		(property "Value" "L_1u_10A_Bourns-SRP4021HMT"
			(at -2.85 3.4 0)
			(layer "F.Fab")
			(hide yes)
			(effects
				(font
					(size 0.7 0.7)
					(thickness 0.15)
				)
				(justify right top)
			)
		)
		(property "Datasheet" "https://www.mouser.com/datasheet/2/54/Bourns_04_01_2025_SRP4021HMT_Datasheet-3580094.pdf"
			(at 0 0 0)
			(layer "F.Fab")
			(hide yes)
			(effects
				(font
					(size 0.7 0.7)
					(thickness 0.15)
				)
				(justify right top)
			)
		)
		(property "Description" "Power Inductors - SMD Ind,4.1x4.2x1.9mm,1uH+/-20%,10A, Shielded"
			(at 0 0 0)
			(layer "F.Fab")
			(hide yes)
			(effects
				(font
					(size 0.7 0.7)
					(thickness 0.15)
				)
				(justify right top)
			)
		)
		(property "Val" "1u/10A"
			(at 0 0 180)
			(unlocked yes)
			(layer "F.Fab")
			(hide yes)
			(effects
				(font
					(size 1 1)
					(thickness 0.15)
				)
			)
		)
		(property "Manufacturer" "Bourns"
			(at 0 0 180)
			(unlocked yes)
			(layer "F.Fab")
			(hide yes)
			(effects
				(font
					(size 1 1)
					(thickness 0.15)
				)
			)
		)
		(property "MPN" "SRP4021HMT-1R0M"
			(at 0 0 180)
			(unlocked yes)
			(layer "F.Fab")
			(hide yes)
			(effects
				(font
					(size 1 1)
					(thickness 0.15)
				)
			)
		)
		(property "ISat" ""
			(at 0 0 180)
			(unlocked yes)
			(layer "F.Fab")
			(hide yes)
			(effects
				(font
					(size 1 1)
					(thickness 0.15)
				)
			)
		)
		(property "Isat" "8A"
			(at 0 0 180)
			(unlocked yes)
			(layer "F.Fab")
			(hide yes)
			(effects
				(font
					(size 1 1)
					(thickness 0.15)
				)
			)
		)
		(property "IMax" ""
			(at 0 0 180)
			(unlocked yes)
			(layer "F.Fab")
			(hide yes)
			(effects
				(font
					(size 1 1)
					(thickness 0.15)
				)
			)
		)
		(property "Imax" "10A"
			(at 0 0 180)
			(unlocked yes)
			(layer "F.Fab")
			(hide yes)
			(effects
				(font
					(size 1 1)
					(thickness 0.15)
				)
			)
		)
		(property "Size" "4.2x4.1"
			(at 0 0 180)
			(unlocked yes)
			(layer "F.Fab")
			(hide yes)
			(effects
				(font
					(size 1 1)
					(thickness 0.15)
				)
			)
		)
		(property "Author" "Antmicro"
			(at 0 0 180)
			(unlocked yes)
			(layer "F.Fab")
			(hide yes)
			(effects
				(font
					(size 1 1)
					(thickness 0.15)
				)
			)
		)
		(property "License" "Apache-2.0"
			(at 0 0 180)
			(unlocked yes)
			(layer "F.Fab")
			(hide yes)
			(effects
				(font
					(size 1 1)
					(thickness 0.15)
				)
			)
		)
		(sheetname "/Power/")
		(sheetfile "power.kicad_sch")
		(attr smd)
		(fp_line
			(start -0.8 2.05)
			(end 0.8 2.05)
			(stroke
				(width 0.15)
				(type solid)
			)
			(layer "F.SilkS")
		)
		(fp_line
			(start -0.8 -2.05)
			(end 0.8 -2.05)
			(stroke
				(width 0.15)
				(type solid)
			)
			(layer "F.SilkS")
		)
		(fp_rect
			(start -2.85 -2.3)
			(end 2.85 2.3)
			(stroke
				(width 0.05)
				(type solid)
			)
			(fill no)
			(layer "F.CrtYd")
		)
		(fp_rect
			(start -2 -2.05)
			(end 2 2.05)
			(stroke
				(width 0.15)
				(type solid)
			)
			(fill no)
			(layer "F.Fab")
		)
		(pad "1" smd rect
			(at 1.85 0)
			(size 1.5 3.5)
			(layers "F.Cu" "F.Mask" "F.Paste")
			(net 335 "/Power/1V88_SW")
			(pintype "passive")
		)
		(pad "2" smd rect
			(at -1.85 0)
			(size 1.5 3.5)
			(layers "F.Cu" "F.Mask" "F.Paste")
			(net 310 "/Power/+1V88_OUT")
			(pintype "passive")
		)
	)
	(footprint "antmicro-footprints:R_0402_1005Metric"
		(layer "F.Cu")
		(at 92.85 60.6)
		(descr "Resistor SMD 0402")
		(tags "resistor SMD 0402")
		(property "Reference" "R127"
			(at -1.47 0.6 0)
			(layer "F.SilkS")
			(effects
				(font
					(size 0.7 0.7)
					(thickness 0.15)
				)
				(justify left top)
			)
		)
		(property "Value" "R_1k_0402"
			(at -1.011843 1.772047 0)
			(layer "F.Fab")
			(hide yes)
			(effects
				(font
					(size 0.7 0.7)
					(thickness 0.15)
				)
				(justify left bottom)
			)
		)
		(property "Datasheet" "https://www.bourns.com/docs/product-datasheets/cr.pdf"
			(at 0 0 0)
			(layer "F.Fab")
			(hide yes)
			(effects
				(font
					(size 1.27 1.27)
					(thickness 0.15)
				)
			)
		)
		(property "Description" "SMD Chip Resistor, 1 kohm, ± 1%, 63 mW, 0402 [1005 Metric], Thick Film, General Purpose"
			(at 0 0 0)
			(layer "F.Fab")
			(hide yes)
			(effects
				(font
					(size 1.27 1.27)
					(thickness 0.15)
				)
			)
		)
		(property "MPN" "CR0402-FX-1001GLF"
			(at 0 0 0)
			(unlocked yes)
			(layer "F.Fab")
			(hide yes)
			(effects
				(font
					(size 1 1)
					(thickness 0.15)
				)
			)
		)
		(property "Manufacturer" "Bourns"
			(at 0 0 0)
			(unlocked yes)
			(layer "F.Fab")
			(hide yes)
			(effects
				(font
					(size 1 1)
					(thickness 0.15)
				)
			)
		)
		(property "License" "Apache-2.0"
			(at 0 0 0)
			(unlocked yes)
			(layer "F.Fab")
			(hide yes)
			(effects
				(font
					(size 1 1)
					(thickness 0.15)
				)
			)
		)
		(property "Author" "Antmicro"
			(at 0 0 0)
			(unlocked yes)
			(layer "F.Fab")
			(hide yes)
			(effects
				(font
					(size 1 1)
					(thickness 0.15)
				)
			)
		)
		(property "Val" "1k"
			(at 0 0 0)
			(unlocked yes)
			(layer "F.Fab")
			(hide yes)
			(effects
				(font
					(size 1 1)
					(thickness 0.15)
				)
			)
		)
		(property "Tolerance" "1%"
			(at 0 0 0)
			(unlocked yes)
			(layer "F.Fab")
			(hide yes)
			(effects
				(font
					(size 1 1)
					(thickness 0.15)
				)
			)
		)
		(sheetname "/OCuLink/")
		(sheetfile "oculink.kicad_sch")
		(attr smd)
		(fp_rect
			(start -0.925 -0.47)
			(end 0.925 0.47)
			(stroke
				(width 0.05)
				(type default)
			)
			(fill no)
			(layer "F.CrtYd")
		)
		(fp_rect
			(start -0.5 -0.25)
			(end 0.5 0.25)
			(stroke
				(width 0.15)
				(type solid)
			)
			(fill no)
			(layer "F.Fab")
		)
		(pad "1" smd roundrect
			(at -0.48 0)
			(size 0.59 0.64)
			(layers "F.Cu" "F.Mask" "F.Paste")
			(roundrect_rratio 0.25)
			(net 410 "Net-(D15-A)")
			(pintype "passive")
		)
		(pad "2" smd roundrect
			(at 0.48 0)
			(size 0.59 0.64)
			(layers "F.Cu" "F.Mask" "F.Paste")
			(roundrect_rratio 0.25)
			(net 90 "+3V3_AUX")
			(pintype "passive")
		)
	)
	(footprint "antmicro-footprints:C_0402_1005Metric"
		(layer "F.Cu")
		(at 98.498001 62.778655 -90)
		(descr "Capacitor SMD 0402")
		(tags "capacitor SMD 0402")
		(property "Reference" "C194"
			(at 1.806345 -2.451999 270)
			(layer "F.SilkS")
			(effects
				(font
					(size 0.7 0.7)
					(thickness 0.15)
				)
				(justify left bottom)
			)
		)
		(property "Value" "C_220n_16V_0402"
			(at -1.022927 2.155213 270)
			(layer "F.Fab")
			(hide yes)
			(effects
				(font
					(size 0.7 0.7)
					(thickness 0.15)
				)
				(justify left bottom)
			)
		)
		(property "Datasheet" "https://www.murata.com/products/productdetail?partno=GRM155R71C224KA12%23"
			(at 0 0 270)
			(layer "F.Fab")
			(hide yes)
			(effects
				(font
					(size 1.27 1.27)
					(thickness 0.15)
				)
			)
		)
		(property "Description" "SMD Multilayer Ceramic Capacitor, 0.22 µF, 16 V, 0402 [1005 Metric], ± 10%, X7R, GRM Series"
			(at 0 0 270)
			(layer "F.Fab")
			(hide yes)
			(effects
				(font
					(size 1.27 1.27)
					(thickness 0.15)
				)
			)
		)
		(property "MPN" "GRM155R71C224KA12D"
			(at 0 0 270)
			(unlocked yes)
			(layer "F.Fab")
			(hide yes)
			(effects
				(font
					(size 1 1)
					(thickness 0.15)
				)
			)
		)
		(property "Manufacturer" "Murata"
			(at 0 0 270)
			(unlocked yes)
			(layer "F.Fab")
			(hide yes)
			(effects
				(font
					(size 1 1)
					(thickness 0.15)
				)
			)
		)
		(property "License" "Apache-2.0"
			(at 0 0 270)
			(unlocked yes)
			(layer "F.Fab")
			(hide yes)
			(effects
				(font
					(size 1 1)
					(thickness 0.15)
				)
			)
		)
		(property "Author" "Antmicro"
			(at 0 0 270)
			(unlocked yes)
			(layer "F.Fab")
			(hide yes)
			(effects
				(font
					(size 1 1)
					(thickness 0.15)
				)
			)
		)
		(property "Val" "220n"
			(at 0 0 270)
			(unlocked yes)
			(layer "F.Fab")
			(hide yes)
			(effects
				(font
					(size 1 1)
					(thickness 0.15)
				)
			)
		)
		(property "Voltage" "16V"
			(at 0 0 270)
			(unlocked yes)
			(layer "F.Fab")
			(hide yes)
			(effects
				(font
					(size 1 1)
					(thickness 0.15)
				)
			)
		)
		(property "Dielectric" "X7R"
			(at 0 0 270)
			(unlocked yes)
			(layer "F.Fab")
			(hide yes)
			(effects
				(font
					(size 1 1)
					(thickness 0.15)
				)
			)
		)
		(sheetname "/X710-AT2 PCIe/")
		(sheetfile "x710-at2-pcie.kicad_sch")
		(attr smd)
		(fp_rect
			(start -0.925 -0.47)
			(end 0.925 0.47)
			(stroke
				(width 0.05)
				(type default)
			)
			(fill no)
			(layer "F.CrtYd")
		)
		(fp_line
			(start -0.494 0.248)
			(end -0.494 -0.25)
			(stroke
				(width 0.15)
				(type solid)
			)
			(layer "F.Fab")
		)
		(fp_line
			(start 0.504 0.248)
			(end -0.494 0.248)
			(stroke
				(width 0.15)
				(type solid)
			)
			(layer "F.Fab")
		)
		(fp_line
			(start -0.494 -0.25)
			(end 0.504 -0.25)
			(stroke
				(width 0.15)
				(type solid)
			)
			(layer "F.Fab")
		)
		(fp_line
			(start 0.504 -0.25)
			(end 0.504 0.248)
			(stroke
				(width 0.15)
				(type solid)
			)
			(layer "F.Fab")
		)
		(pad "1" smd roundrect
			(at -0.48 0 270)
			(size 0.59 0.64)
			(layers "F.Cu" "F.Mask" "F.Paste")
			(roundrect_rratio 0.25)
			(net 21 "/OCuLink/PCIe_{x4}.TX2+")
			(pintype "passive")
		)
		(pad "2" smd roundrect
			(at 0.48 0 270)
			(size 0.59 0.64)
			(layers "F.Cu" "F.Mask" "F.Paste")
			(roundrect_rratio 0.25)
			(net 40 "/X710-AT2 PCIe/PCIe_{x4}_AC.TX2+")
			(pintype "passive")
		)
	)
	(footprint "antmicro-footprints:MP_Terminal_M3_THT_7760"
		(layer "F.Cu")
		(at 110.46 139.7)
		(property "Reference" "J5"
			(at -1.68 -1.9 0)
			(unlocked yes)
			(layer "F.SilkS")
			(effects
				(font
					(size 0.7 0.7)
					(thickness 0.15)
				)
				(justify left bottom)
			)
		)
		(property "Value" "MP_Terminal_M3_THT_7760"
			(at -1.68 11.43 0)
			(unlocked yes)
			(layer "F.Fab")
			(hide yes)
			(effects
				(font
					(size 0.7 0.7)
					(thickness 0.15)
				)
				(justify left bottom)
			)
		)
		(property "Datasheet" "https://www.mouser.com/datasheet/2/215/7760-741244.pdf"
			(at 0 0 0)
			(unlocked yes)
			(layer "F.Fab")
			(hide yes)
			(effects
				(font
					(size 0.7 0.7)
					(thickness 0.15)
				)
				(justify left bottom)
			)
		)
		(property "Description" "PCB Terminal, 90° THT, Brass, Tin"
			(at 0 0 0)
			(unlocked yes)
			(layer "F.Fab")
			(hide yes)
			(effects
				(font
					(size 0.7 0.7)
					(thickness 0.15)
				)
				(justify left bottom)
			)
		)
		(property "MPN" "7760"
			(at 0 0 0)
			(unlocked yes)
			(layer "F.Fab")
			(hide yes)
			(effects
				(font
					(size 1 1)
					(thickness 0.15)
				)
			)
		)
		(property "Manufacturer" "Keystone Electronics"
			(at 0 0 0)
			(unlocked yes)
			(layer "F.Fab")
			(hide yes)
			(effects
				(font
					(size 1 1)
					(thickness 0.15)
				)
			)
		)
		(property "Author" "Antmicro"
			(at 0 0 0)
			(unlocked yes)
			(layer "F.Fab")
			(hide yes)
			(effects
				(font
					(size 1 1)
					(thickness 0.15)
				)
			)
		)
		(property "License" "Apache-2.0"
			(at 0 0 0)
			(unlocked yes)
			(layer "F.Fab")
			(hide yes)
			(effects
				(font
					(size 1 1)
					(thickness 0.15)
				)
			)
		)
		(sheetname "/2xRJ45/")
		(sheetfile "2xrj45.kicad_sch")
		(attr through_hole allow_soldermask_bridges)
		(fp_line
			(start -0.42 3.255)
			(end -0.42 1.745)
			(stroke
				(width 0.15)
				(type solid)
			)
			(layer "F.SilkS")
		)
		(fp_line
			(start -0.42 6.745)
			(end -0.42 10.08)
			(stroke
				(width 0.15)
				(type solid)
			)
			(layer "F.SilkS")
		)
		(fp_line
			(start -0.42 10.08)
			(end 7.91 10.08)
			(stroke
				(width 0.15)
				(type solid)
			)
			(layer "F.SilkS")
		)
		(fp_line
			(start 1.745 -1.4)
			(end 5.745 -1.4)
			(stroke
				(width 0.15)
				(type solid)
			)
			(layer "F.SilkS")
		)
		(fp_line
			(start 7.91 3.255)
			(end 7.91 1.745)
			(stroke
				(width 0.15)
				(type solid)
			)
			(layer "F.SilkS")
		)
		(fp_line
			(start 7.91 10.08)
			(end 7.91 6.745)
			(stroke
				(width 0.15)
				(type solid)
			)
			(layer "F.SilkS")
		)
		(fp_rect
			(start -1.68 -1.68)
			(end 9.16 10.33)
			(stroke
				(width 0.05)
				(type solid)
			)
			(fill no)
			(layer "F.CrtYd")
		)
		(fp_rect
			(start -0.42 -1.4)
			(end 7.91 10.08)
			(stroke
				(width 0.15)
				(type solid)
			)
			(fill no)
			(layer "F.Fab")
		)
		(pad "1" thru_hole circle
			(at 0 0 90)
			(size 2.85 2.85)
			(drill 1.9)
			(layers "*.Cu" "*.Mask")
			(remove_unused_layers no)
			(net 28 "GND")
			(pintype "passive")
		)
		(pad "1" thru_hole circle
			(at 0 5 90)
			(size 2.85 2.85)
			(drill 1.9)
			(layers "*.Cu" "*.Mask")
			(remove_unused_layers no)
			(net 28 "GND")
			(pintype "passive")
		)
		(pad "1" thru_hole circle
			(at 7.49 0 90)
			(size 2.85 2.85)
			(drill 1.9)
			(layers "*.Cu" "*.Mask")
			(remove_unused_layers no)
			(net 28 "GND")
			(pintype "passive")
		)
		(pad "1" thru_hole circle
			(at 7.49 5 90)
			(size 2.85 2.85)
			(drill 1.9)
			(layers "*.Cu" "*.Mask")
			(remove_unused_layers no)
			(net 28 "GND")
			(pintype "passive")
		)
	)
	(footprint "antmicro-footprints:C_0603_1608Metric_EIA"
		(layer "F.Cu")
		(at 74.899998 83.909996 -90)
		(descr "Capacitor SMD 0603, IPC-7351 Density Level A")
		(tags "Capacitor 0603")
		(property "Reference" "C205"
			(at -3.999996 0.029998 90)
			(layer "F.SilkS")
			(effects
				(font
					(size 0.7 0.7)
					(thickness 0.15)
				)
				(justify right top)
			)
		)
		(property "Value" "C_22u_16V_0603"
			(at -1.42757 1.770288 90)
			(layer "F.Fab")
			(hide yes)
			(effects
				(font
					(size 0.7 0.7)
					(thickness 0.15)
				)
				(justify right top)
			)
		)
		(property "Datasheet" "https://product.samsungsem.com/mlcc/CL10A226MO7JZN.do"
			(at 0 0 90)
			(layer "F.Fab")
			(hide yes)
			(effects
				(font
					(size 1.27 1.27)
					(thickness 0.15)
				)
			)
		)
		(property "Description" "SMD Multilayer Ceramic Capacitor"
			(at 0 0 90)
			(layer "F.Fab")
			(hide yes)
			(effects
				(font
					(size 1.27 1.27)
					(thickness 0.15)
				)
			)
		)
		(property "MPN" "CL10A226MO7JZNC"
			(at 0 0 270)
			(unlocked yes)
			(layer "F.Fab")
			(hide yes)
			(effects
				(font
					(size 1 1)
					(thickness 0.15)
				)
			)
		)
		(property "Manufacturer" "Samsung Electro-Mechanics"
			(at 0 0 270)
			(unlocked yes)
			(layer "F.Fab")
			(hide yes)
			(effects
				(font
					(size 1 1)
					(thickness 0.15)
				)
			)
		)
		(property "License" "Apache-2.0"
			(at 0 0 270)
			(unlocked yes)
			(layer "F.Fab")
			(hide yes)
			(effects
				(font
					(size 1 1)
					(thickness 0.15)
				)
			)
		)
		(property "Author" "Antmicro"
			(at 0 0 270)
			(unlocked yes)
			(layer "F.Fab")
			(hide yes)
			(effects
				(font
					(size 1 1)
					(thickness 0.15)
				)
			)
		)
		(property "Val" "22u"
			(at 0 0 270)
			(unlocked yes)
			(layer "F.Fab")
			(hide yes)
			(effects
				(font
					(size 1 1)
					(thickness 0.15)
				)
			)
		)
		(property "Voltage" "16V"
			(at 0 0 270)
			(unlocked yes)
			(layer "F.Fab")
			(hide yes)
			(effects
				(font
					(size 1 1)
					(thickness 0.15)
				)
			)
		)
		(property "Dielectric" ""
			(at 0 0 270)
			(unlocked yes)
			(layer "F.Fab")
			(hide yes)
			(effects
				(font
					(size 1 1)
					(thickness 0.15)
				)
			)
		)
		(property "Public" "False"
			(at 0 0 270)
			(unlocked yes)
			(layer "F.Fab")
			(hide yes)
			(effects
				(font
					(size 1 1)
					(thickness 0.15)
				)
			)
		)
		(sheetname "/Power/")
		(sheetfile "power.kicad_sch")
		(attr smd)
		(fp_line
			(start -0.15 0.55)
			(end 0.15 0.55)
			(stroke
				(width 0.15)
				(type solid)
			)
			(layer "F.SilkS")
		)
		(fp_line
			(start -0.15 -0.55)
			(end 0.15 -0.55)
			(stroke
				(width 0.15)
				(type solid)
			)
			(layer "F.SilkS")
		)
		(fp_rect
			(start -1.25 -0.65)
			(end 1.25 0.65)
			(stroke
				(width 0.05)
				(type solid)
			)
			(fill no)
			(layer "F.CrtYd")
		)
		(fp_rect
			(start -0.8 -0.45)
			(end 0.8 0.45)
			(stroke
				(width 0.15)
				(type solid)
			)
			(fill no)
			(layer "F.Fab")
		)
		(pad "1" smd roundrect
			(at -0.7 0 270)
			(size 0.8 1.1)
			(layers "F.Cu" "F.Mask" "F.Paste")
			(roundrect_rratio 0.2)
			(net 28 "GND")
			(pintype "passive")
		)
		(pad "2" smd roundrect
			(at 0.7 0 270)
			(size 0.8 1.1)
			(layers "F.Cu" "F.Mask" "F.Paste")
			(roundrect_rratio 0.2)
			(net 255 "/Power/+3V3_OUT")
			(pintype "passive")
		)
	)
)
